# BASEBOARD_FAB2 (Tioga Pass) — schematic netlist excerpt (pin names and nets, part order shuffled) for the footprints in the layout excerpt that follows; sources: Cadence DE-HDL packaged netlist, KiCad conversion of Wiwynn_Tioga_Pass_MB.brd

J6U1  SCONN288_H44441003  SCONN  pkg PIP  page 46
  \12v\(1)  = P12V_NVDIMM_ABC
  VSS(93)  = GND
  DQ(4)  = M_B_DQ<4>
  VSS(92)  = GND
  DQ(0)  = M_B_DQ<0>
  VSS(91)  = GND
  DQS9P  = M_B_DQS_DP<9>
  DQS9N  = M_B_DQS_DN<9>
  VSS(90)  = GND
  DQ(6)  = M_B_DQ<6>
  VSS(89)  = GND
  DQ(2)  = M_B_DQ<2>
  VSS(88)  = GND
  DQ(12)  = M_B_DQ<12>
  VSS(87)  = GND
  DQ(8)  = M_B_DQ<8>
  VSS(86)  = GND
  DQS10P  = M_B_DQS_DP<10>
  DQS10N  = M_B_DQS_DN<10>
  VSS(85)  = GND
  DQ(14)  = M_B_DQ<14>
  VSS(84)  = GND
  DQ(10)  = M_B_DQ<10>
  VSS(83)  = GND
  DQ(20)  = M_B_DQ<20>
  VSS(82)  = GND
  DQ(16)  = M_B_DQ<16>
  VSS(81)  = GND
  DQS11P  = M_B_DQS_DP<11>
  DQS11N  = M_B_DQS_DN<11>
  VSS(80)  = GND
  DQ(22)  = M_B_DQ<22>
  VSS(79)  = GND
  DQ(18)  = M_B_DQ<18>
  VSS(78)  = GND
  DQ(28)  = M_B_DQ<28>
  VSS(77)  = GND
  DQ(24)  = M_B_DQ<24>
  VSS(76)  = GND
  DQS12P  = M_B_DQS_DP<12>
  DQS12N  = M_B_DQS_DN<12>
  VSS(75)  = GND
  DQ(30)  = M_B_DQ<30>
  VSS(74)  = GND
  DQ(26)  = M_B_DQ<26>
  VSS(73)  = GND
  CB(4)  = M_B_ECC<4>
  VSS(72)  = GND
  CB(0)  = M_B_ECC<0>
  VSS(71)  = GND
  DQS17P  = M_B_DQS_DP<17>
  DQS17N  = M_B_DQS_DN<17>
  VSS(70)  = GND
  CB(6)  = M_B_ECC<6>
  VSS(69)  = GND
  CB(2)  = M_B_ECC<2>
  VSS(68)  = GND
  RESET_N  = M_ABC_RST_N
  VDD(25)  = PVDDQ_ABC
  CKE(0)  = M_B_CKE<2>
  VDD(24)  = PVDDQ_ABC
  ACT_N  = M_B_ACT_N
  BG(0)  = M_B_BG<0>
  VDD(23)  = PVDDQ_ABC
  A12  = M_B_MA<12>
  A9  = M_B_MA<9>
  VDD(22)  = PVDDQ_ABC
  A8  = M_B_MA<8>
  A6  = M_B_MA<6>
  VDD(21)  = PVDDQ_ABC
  A3  = M_B_MA<3>
  A1  = M_B_MA<1>
  VDD(20)  = PVDDQ_ABC
  CK0P  = M_B_CLK_DP<2>
  CK0N  = M_B_CLK_DN<2>
  VDD(19)  = PVDDQ_ABC
  VTT(1)  = PVTT_ABC
  EVENT_N  = FM_DIMM_EVENT_COD_N
  A0  = M_B_MA<0>
  VDD(18)  = PVDDQ_ABC
  BA(0)  = M_B_BA<0>
  A16_RAS_N  = M_B_MA<16>
  VDD(17)  = PVDDQ_ABC
  S0_N  = M_B_CS_N<4>
  VDD(16)  = PVDDQ_ABC
  A15_CAS_N  = M_B_MA<15>
  ODT(0)  = M_B_ODT<2>
  VDD(15)  = PVDDQ_ABC
  S1_N  = M_B_CS_N<5>
  VDD(14)  = PVDDQ_ABC
  ODT(1)  = M_B_ODT<3>
  VDD(13)  = PVDDQ_ABC
  S2_N_C(0)  = M_B_CS_N<6>
  VSS(67)  = GND
  DQ(36)  = M_B_DQ<36>
  VSS(66)  = GND
  DQ(32)  = M_B_DQ<32>
  VSS(65)  = GND
  DQS13P  = M_B_DQS_DP<13>
  DQS13N  = M_B_DQS_DN<13>
  VSS(64)  = GND
  DQ(38)  = M_B_DQ<38>
  VSS(63)  = GND
  DQ(34)  = M_B_DQ<34>
  VSS(62)  = GND
  DQ(44)  = M_B_DQ<44>
  VSS(61)  = GND
  DQ(40)  = M_B_DQ<40>
  VSS(60)  = GND
  DQS14P  = M_B_DQS_DP<14>
  DQS14N  = M_B_DQS_DN<14>
  VSS(59)  = GND
  DQ(46)  = M_B_DQ<46>
  VSS(58)  = GND
  DQ(42)  = M_B_DQ<42>
  VSS(57)  = GND
  DQ(52)  = M_B_DQ<52>
  VSS(56)  = GND
  DQ(48)  = M_B_DQ<48>
  VSS(55)  = GND
  DQS15P  = M_B_DQS_DP<15>
  DQS15N  = M_B_DQS_DN<15>
  VSS(54)  = GND
  DQ(54)  = M_B_DQ<54>
  VSS(53)  = GND
  DQ(50)  = M_B_DQ<50>
  VSS(52)  = GND
  DQ(60)  = M_B_DQ<60>
  VSS(51)  = GND
  DQ(56)  = M_B_DQ<56>
  VSS(50)  = GND
  DQS16P  = M_B_DQS_DP<16>
  DQS16N  = M_B_DQS_DN<16>
  VSS(49)  = GND
  DQ(62)  = M_B_DQ<62>
  VSS(48)  = GND
  DQ(58)  = M_B_DQ<58>
  VSS(47)  = GND
  SA(0)  = PVPP_ABC
  SA(1)  = PVPP_ABC
  SCL  = SMB_DDR_ABC_VPP_SCL
  VPP(4)  = PVPP_ABC
  VPP(3)  = PVPP_ABC
  RFU(2)  = TP_CH_B_DIMM_B1_RFU_2
  \12v\(0)  = P12V_NVDIMM_ABC
  VREFCA  = M_B_VREF
  VSS(46)  = GND
  DQ(5)  = M_B_DQ<5>
  VSS(45)  = GND
  DQ(1)  = M_B_DQ<1>
  VSS(44)  = GND
  DQS0N  = M_B_DQS_DN<0>
  DQS0P  = M_B_DQS_DP<0>
  VSS(43)  = GND
  DQ(7)  = M_B_DQ<7>
  VSS(42)  = GND
  DQ(3)  = M_B_DQ<3>
  VSS(41)  = GND
  DQ(13)  = M_B_DQ<13>
  VSS(40)  = GND
  DQ(9)  = M_B_DQ<9>
  VSS(39)  = GND
  DQS1N  = M_B_DQS_DN<1>
  DQS1P  = M_B_DQS_DP<1>
  VSS(38)  = GND
  DQ(15)  = M_B_DQ<15>
  VSS(37)  = GND
  DQ(11)  = M_B_DQ<11>
  VSS(36)  = GND
  DQ(21)  = M_B_DQ<21>
  VSS(35)  = GND
  DQ(17)  = M_B_DQ<17>
  VSS(34)  = GND
  DQS2N  = M_B_DQS_DN<2>
  DQS2P  = M_B_DQS_DP<2>
  VSS(33)  = GND
  DQ(23)  = M_B_DQ<23>
  VSS(32)  = GND
  DQ(19)  = M_B_DQ<19>
  VSS(31)  = GND
  DQ(29)  = M_B_DQ<29>
  VSS(30)  = GND
  DQ(25)  = M_B_DQ<25>
  VSS(29)  = GND
  DQS3N  = M_B_DQS_DN<3>
  DQS3P  = M_B_DQS_DP<3>
  VSS(28)  = GND
  DQ(31)  = M_B_DQ<31>
  VSS(27)  = GND
  DQ(27)  = M_B_DQ<27>
  VSS(26)  = GND
  CB(5)  = M_B_ECC<5>
  VSS(25)  = GND
  CB(1)  = M_B_ECC<1>
  VSS(24)  = GND
  DQS8N  = M_B_DQS_DN<8>
  DQS8P  = M_B_DQS_DP<8>
  VSS(23)  = GND
  CB(7)  = M_B_ECC<7>
  VSS(22)  = GND
  CB(3)  = M_B_ECC<3>
  VSS(21)  = GND
  CKE(1)  = M_B_CKE<3>
  VDD(12)  = PVDDQ_ABC
  RFU(0)  = TP_CH_B_DIMM_B1_RFU_0
  VDD(11)  = PVDDQ_ABC
  BG(1)  = M_B_BG<1>
  ALERT_N  = M_B_ALERT_N
  VDD(10)  = PVDDQ_ABC
  A11  = M_B_MA<11>
  A7  = M_B_MA<7>
  VDD(9)  = PVDDQ_ABC
  A5  = M_B_MA<5>
  A4  = M_B_MA<4>
  VDD(8)  = PVDDQ_ABC
  A2  = M_B_MA<2>
  VDD(7)  = PVDDQ_ABC
  CK1P  = M_B_CLK_DP<3>
  CK1N  = M_B_CLK_DN<3>
  VDD(6)  = PVDDQ_ABC
  VTT(0)  = PVTT_ABC
  PAR  = M_B_PAR
  VDD(5)  = PVDDQ_ABC
  BA(1)  = M_B_BA<1>
  A10  = M_B_MA<10>
  VDD(4)  = PVDDQ_ABC
  RFU(1)  = TP_CH_B_DIMM_B1_RFU_1
  A14_WE_N  = M_B_MA<14>
  VDD(3)  = PVDDQ_ABC
  SAVE_N_NC  = FM_ADR_COMPLETE_ABC_N
  VDD(2)  = PVDDQ_ABC
  A13  = M_B_MA<13>
  VDD(1)  = PVDDQ_ABC
  A17  = M_B_MA<17>
  C(2)  = M_B_C<2>
  VDD(0)  = PVDDQ_ABC
  S3_N_C(1)  = M_B_CS_N<7>
  SA(2)  = GND
  VSS(20)  = GND
  DQ(37)  = M_B_DQ<37>
  VSS(19)  = GND
  DQ(33)  = M_B_DQ<33>
  VSS(18)  = GND
  DQS4N  = M_B_DQS_DN<4>
  DQS4P  = M_B_DQS_DP<4>
  VSS(17)  = GND
  DQ(39)  = M_B_DQ<39>
  VSS(16)  = GND
  DQ(35)  = M_B_DQ<35>
  VSS(15)  = GND
  DQ(45)  = M_B_DQ<45>
  VSS(14)  = GND
  DQ(41)  = M_B_DQ<41>
  VSS(13)  = GND
  DQS5N  = M_B_DQS_DN<5>
  DQS5P  = M_B_DQS_DP<5>
  VSS(12)  = GND
  DQ(47)  = M_B_DQ<47>
  VSS(11)  = GND
  DQ(43)  = M_B_DQ<43>
  VSS(10)  = GND
  DQ(53)  = M_B_DQ<53>
  VSS(9)  = GND
  DQ(49)  = M_B_DQ<49>
  VSS(8)  = GND
  DQS6N  = M_B_DQS_DN<6>
  DQS6P  = M_B_DQS_DP<6>
  VSS(7)  = GND
  DQ(55)  = M_B_DQ<55>
  VSS(6)  = GND
  DQ(51)  = M_B_DQ<51>
  VSS(5)  = GND
  DQ(61)  = M_B_DQ<61>
  VSS(4)  = GND
  DQ(57)  = M_B_DQ<57>
  VSS(3)  = GND
  DQS7N  = M_B_DQS_DN<7>
  DQS7P  = M_B_DQS_DP<7>
  VSS(2)  = GND
  DQ(63)  = M_B_DQ<63>
  VSS(1)  = GND
  DQ(59)  = M_B_DQ<59>
  VSS(0)  = GND
  VDDSPD  = PVPP_ABC
  SDA  = SMB_DDR_ABC_VPP_SDA
  VPP(1)  = PVPP_ABC
  VPP(0)  = PVPP_ABC
  VPP(2)  = PVPP_ABC

(kicad_pcb
	(version 20260206)
	(generator "pcbnew")
	(generator_version "10.0")
	(general
		(thickness 1.6)
		(legacy_teardrops no)
	)
	(paper "A4")
	(title_block
		(title "Wiwynn_Tioga_Pass_MB.brd")
		(comment 1 "Tioga Pass / footprint 2988 of 4770 (J6U1), pads 202-249 of 291")
	)
	(layers
		(0 "F.Cu" signal "TOP")
		(4 "In1.Cu" signal "L2GND")
		(6 "In2.Cu" signal "L3")
		(8 "In3.Cu" signal "L4GND")
		(10 "In4.Cu" signal "L5")
		(12 "In5.Cu" signal "L6GND")
		(14 "In6.Cu" signal "L7VCC")
		(16 "In7.Cu" signal "L8VCC")
		(18 "In8.Cu" signal "L9GND")
		(20 "In9.Cu" signal "L10")
		(22 "In10.Cu" signal "L11GND")
		(24 "In11.Cu" signal "L12")
		(26 "In12.Cu" signal "L13GND")
		(2 "B.Cu" signal "BOTTOM")
		(9 "F.Adhes" user "F.Adhesive")
		(11 "B.Adhes" user "B.Adhesive")
		(13 "F.Paste" user "Package Geometry/Pastemask Top")
		(15 "B.Paste" user "Package Geometry/Pastemask Bottom")
		(5 "F.SilkS" user "Ref Des/Silkscreen Top")
		(7 "B.SilkS" user "Ref Des/Silkscreen Bottom")
		(1 "F.Mask" user "Board Geometry/Soldermask Top")
		(3 "B.Mask" user "Board Geometry/Soldermask Bottom")
		(17 "Dwgs.User" user "User.Drawings")
		(19 "Cmts.User" user "User.Comments")
		(21 "Eco1.User" user "User.Eco1")
		(23 "Eco2.User" user "User.Eco2")
		(25 "Edge.Cuts" user "Board Geometry/Outline")
		(27 "Margin" user)
		(31 "F.CrtYd" user "Package Geometry/Place Bound Top")
		(29 "B.CrtYd" user "Package Geometry/Place Bound Bottom")
		(35 "F.Fab" user "Ref Des/Assembly Top")
		(33 "B.Fab" user "Ref Des/Assembly Bottom")
	)
	(footprint ""
		(layer "B.Cu")
		(at 194.700398 -15.222982 90)
		(property "Reference" "J6U1"
			(at 2.530348 39.10711 0)
			(unlocked yes)
			(layer "B.SilkS")
			(effects
				(font
					(size 0.7874 0.5842)
					(thickness 0.1524)
				)
				(justify left mirror)
			)
		)
		(property "Value" ""
			(at 0 0 90)
			(layer "B.Fab")
			(effects
				(font
					(size 1.27 1.27)
				)
				(justify mirror)
			)
		)
		(duplicate_pad_numbers_are_jumpers no)
		(pad "199" smd rect
			(at -4.59994 45.900086 270)
			(size 1.8034 0.508)
			(layers "B.Cu" "B.Mask" "B.Paste")
			(net "M_B_ECC<7>")
		)
		(pad "200" smd rect
			(at -4.59994 46.74997 270)
			(size 1.8034 0.508)
			(layers "B.Cu" "B.Mask" "B.Paste")
			(net "GND")
		)
		(pad "201" smd rect
			(at -4.59994 47.600108 270)
			(size 1.8034 0.508)
			(layers "B.Cu" "B.Mask" "B.Paste")
			(net "M_B_ECC<3>")
		)
		(pad "202" smd rect
			(at -4.59994 48.449992 270)
			(size 1.8034 0.508)
			(layers "B.Cu" "B.Mask" "B.Paste")
			(net "GND")
		)
		(pad "203" smd rect
			(at -4.59994 49.299876 270)
			(size 1.8034 0.508)
			(layers "B.Cu" "B.Mask" "B.Paste")
			(net "M_B_CKE<3>")
		)
		(pad "204" smd rect
			(at -4.59994 50.150014 270)
			(size 1.8034 0.508)
			(layers "B.Cu" "B.Mask" "B.Paste")
			(net "PVDDQ_ABC")
		)
		(pad "205" smd rect
			(at -4.59994 50.999898 270)
			(size 1.8034 0.508)
			(layers "B.Cu" "B.Mask" "B.Paste")
			(net "TP_CH_B_DIMM_B1_RFU_0")
		)
		(pad "206" smd rect
			(at -4.59994 51.850036 270)
			(size 1.8034 0.508)
			(layers "B.Cu" "B.Mask" "B.Paste")
			(net "PVDDQ_ABC")
		)
		(pad "207" smd rect
			(at -4.59994 52.69992 270)
			(size 1.8034 0.508)
			(layers "B.Cu" "B.Mask" "B.Paste")
			(net "M_B_BG<1>")
		)
		(pad "208" smd rect
			(at -4.59994 53.550058 270)
			(size 1.8034 0.508)
			(layers "B.Cu" "B.Mask" "B.Paste")
			(net "M_B_ALERT_N")
		)
		(pad "209" smd rect
			(at -4.59994 54.399942 270)
			(size 1.8034 0.508)
			(layers "B.Cu" "B.Mask" "B.Paste")
			(net "PVDDQ_ABC")
		)
		(pad "210" smd rect
			(at -4.59994 55.25008 270)
			(size 1.8034 0.508)
			(layers "B.Cu" "B.Mask" "B.Paste")
			(net "M_B_MA<11>")
		)
		(pad "211" smd rect
			(at -4.59994 56.099964 270)
			(size 1.8034 0.508)
			(layers "B.Cu" "B.Mask" "B.Paste")
			(net "M_B_MA<7>")
		)
		(pad "212" smd rect
			(at -4.59994 56.950102 270)
			(size 1.8034 0.508)
			(layers "B.Cu" "B.Mask" "B.Paste")
			(net "PVDDQ_ABC")
		)
		(pad "213" smd rect
			(at -4.59994 57.799986 270)
			(size 1.8034 0.508)
			(layers "B.Cu" "B.Mask" "B.Paste")
			(net "M_B_MA<5>")
		)
		(pad "214" smd rect
			(at -4.59994 58.650124 270)
			(size 1.8034 0.508)
			(layers "B.Cu" "B.Mask" "B.Paste")
			(net "M_B_MA<4>")
		)
		(pad "215" smd rect
			(at -4.59994 59.500008 270)
			(size 1.8034 0.508)
			(layers "B.Cu" "B.Mask" "B.Paste")
			(net "PVDDQ_ABC")
		)
		(pad "216" smd rect
			(at -4.59994 60.349892 270)
			(size 1.8034 0.508)
			(layers "B.Cu" "B.Mask" "B.Paste")
			(net "M_B_MA<2>")
		)
		(pad "217" smd rect
			(at -4.59994 61.20003 270)
			(size 1.8034 0.508)
			(layers "B.Cu" "B.Mask" "B.Paste")
			(net "PVDDQ_ABC")
		)
		(pad "218" smd rect
			(at -4.59994 62.049914 270)
			(size 1.8034 0.508)
			(layers "B.Cu" "B.Mask" "B.Paste")
			(net "M_B_CLK_DP<3>")
		)
		(pad "219" smd rect
			(at -4.59994 62.900052 270)
			(size 1.8034 0.508)
			(layers "B.Cu" "B.Mask" "B.Paste")
			(net "M_B_CLK_DN<3>")
		)
		(pad "220" smd rect
			(at -4.59994 63.749936 270)
			(size 1.8034 0.508)
			(layers "B.Cu" "B.Mask" "B.Paste")
			(net "PVDDQ_ABC")
		)
		(pad "221" smd rect
			(at -4.59994 64.600074 270)
			(size 1.8034 0.508)
			(layers "B.Cu" "B.Mask" "B.Paste")
			(net "PVTT_ABC")
		)
		(pad "222" smd rect
			(at -4.59994 70.550024 270)
			(size 1.8034 0.508)
			(layers "B.Cu" "B.Mask" "B.Paste")
			(net "M_B_PAR")
		)
		(pad "223" smd rect
			(at -4.59994 71.399908 270)
			(size 1.8034 0.508)
			(layers "B.Cu" "B.Mask" "B.Paste")
			(net "PVDDQ_ABC")
		)
		(pad "224" smd rect
			(at -4.59994 72.250046 270)
			(size 1.8034 0.508)
			(layers "B.Cu" "B.Mask" "B.Paste")
			(net "M_B_BA<1>")
		)
		(pad "225" smd rect
			(at -4.59994 73.09993 270)
			(size 1.8034 0.508)
			(layers "B.Cu" "B.Mask" "B.Paste")
			(net "M_B_MA<10>")
		)
		(pad "226" smd rect
			(at -4.59994 73.950068 270)
			(size 1.8034 0.508)
			(layers "B.Cu" "B.Mask" "B.Paste")
			(net "PVDDQ_ABC")
		)
		(pad "227" smd rect
			(at -4.59994 74.799952 270)
			(size 1.8034 0.508)
			(layers "B.Cu" "B.Mask" "B.Paste")
			(net "TP_CH_B_DIMM_B1_RFU_1")
		)
		(pad "228" smd rect
			(at -4.59994 75.65009 270)
			(size 1.8034 0.508)
			(layers "B.Cu" "B.Mask" "B.Paste")
			(net "M_B_MA<14>")
		)
		(pad "229" smd rect
			(at -4.59994 76.499974 270)
			(size 1.8034 0.508)
			(layers "B.Cu" "B.Mask" "B.Paste")
			(net "PVDDQ_ABC")
		)
		(pad "230" smd rect
			(at -4.59994 77.350112 270)
			(size 1.8034 0.508)
			(layers "B.Cu" "B.Mask" "B.Paste")
			(net "FM_ADR_COMPLETE_ABC_N")
		)
		(pad "231" smd rect
			(at -4.59994 78.199996 270)
			(size 1.8034 0.508)
			(layers "B.Cu" "B.Mask" "B.Paste")
			(net "PVDDQ_ABC")
		)
		(pad "232" smd rect
			(at -4.59994 79.04988 270)
			(size 1.8034 0.508)
			(layers "B.Cu" "B.Mask" "B.Paste")
			(net "M_B_MA<13>")
		)
		(pad "233" smd rect
			(at -4.59994 79.900018 270)
			(size 1.8034 0.508)
			(layers "B.Cu" "B.Mask" "B.Paste")
			(net "PVDDQ_ABC")
		)
		(pad "234" smd rect
			(at -4.59994 80.749902 270)
			(size 1.8034 0.508)
			(layers "B.Cu" "B.Mask" "B.Paste")
			(net "M_B_MA<17>")
		)
		(pad "235" smd rect
			(at -4.59994 81.60004 270)
			(size 1.8034 0.508)
			(layers "B.Cu" "B.Mask" "B.Paste")
			(net "M_B_C<2>")
		)
		(pad "236" smd rect
			(at -4.59994 82.449924 270)
			(size 1.8034 0.508)
			(layers "B.Cu" "B.Mask" "B.Paste")
			(net "PVDDQ_ABC")
		)
		(pad "237" smd rect
			(at -4.59994 83.300062 270)
			(size 1.8034 0.508)
			(layers "B.Cu" "B.Mask" "B.Paste")
			(net "M_B_CS_N<7>")
		)
		(pad "238" smd rect
			(at -4.59994 84.149946 270)
			(size 1.8034 0.508)
			(layers "B.Cu" "B.Mask" "B.Paste")
			(net "GND")
		)
		(pad "239" smd rect
			(at -4.59994 85.000084 270)
			(size 1.8034 0.508)
			(layers "B.Cu" "B.Mask" "B.Paste")
			(net "GND")
		)
		(pad "240" smd rect
			(at -4.59994 85.849968 270)
			(size 1.8034 0.508)
			(layers "B.Cu" "B.Mask" "B.Paste")
			(net "M_B_DQ<37>")
		)
		(pad "241" smd rect
			(at -4.59994 86.700106 270)
			(size 1.8034 0.508)
			(layers "B.Cu" "B.Mask" "B.Paste")
			(net "GND")
		)
		(pad "242" smd rect
			(at -4.59994 87.54999 270)
			(size 1.8034 0.508)
			(layers "B.Cu" "B.Mask" "B.Paste")
			(net "M_B_DQ<33>")
		)
		(pad "243" smd rect
			(at -4.59994 88.399874 270)
			(size 1.8034 0.508)
			(layers "B.Cu" "B.Mask" "B.Paste")
			(net "GND")
		)
		(pad "244" smd rect
			(at -4.59994 89.250012 270)
			(size 1.8034 0.508)
			(layers "B.Cu" "B.Mask" "B.Paste")
			(net "M_B_DQS_DN<4>")
		)
		(pad "245" smd rect
			(at -4.59994 90.099896 270)
			(size 1.8034 0.508)
			(layers "B.Cu" "B.Mask" "B.Paste")
			(net "M_B_DQS_DP<4>")
		)
		(pad "246" smd rect
			(at -4.59994 90.950034 270)
			(size 1.8034 0.508)
			(layers "B.Cu" "B.Mask" "B.Paste")
			(net "GND")
		)
	)
)
